FILE_TYPE = CONNECTIVITY;
{Allegro Design Entry HDL 17.2-2016 S081 (4005846) 1/11/2022}
"PAGE_NUMBER" = 147;
0"NC";
END.
